FILE_TYPE = CONNECTIVITY;
{Allegro Design Entry HDL 16.6-p007 (v16-6-112F) 10/10/2012}
"PAGE_NUMBER" = 242;
0"NC";
1"PVDDQ_ABC\g";
2"GND\g";
3"GND\g";
4"GND\g";
5"PVDDQ_DEF\g";
6"PVDDQ_ABC\g";
7"GND\g";
8"PVDDQ_DEF\g";
9"GND\g";
10"PVDDQ_DEF\g";
11"GND\g";
12"PVDDQ_ABC\g";
%"GND"
"1","(-7750,1450)","0","mstr_symbols","I1";
;
HDL_POWER"GND"
BODY_TYPE"PLUMBING"
CDS_LIB"mstr_symbols"
SIZE"1B"
BOM_COST"PROC_VRD_VCCIN_CPU0"
ROOM"VDDQ_ABC_PWR_VR"
VOLTAGE"0";
"A\NAC"2;
%"GND"
"1","(-7750,3375)","0","mstr_symbols","I10";
;
HDL_POWER"GND"
BODY_TYPE"PLUMBING"
CDS_LIB"mstr_symbols"
VOLTAGE"0"
ROOM"VDDQ_ABC_PWR_VR"
BOM_COST"PROC_VRD_VCCIN_CPU0"
SIZE"1B";
"A\NAC"3;
%"PVDDQ_ABC"
"1","(-7750,4075)","0","mstr_symbols","I26";
;
HDL_POWER"PVDDQ_ABC"
BODY_TYPE"PLUMBING"
CDS_LIB"mstr_symbols"
VOLTAGE"1.2V"
BOM_COST"PROC_SOCKET "
ROOM"VDDQ_ABC_PWR_VR";
"G\NAC"1;
%"GND"
"1","(-3800,1450)","0","mstr_symbols","I27";
;
HDL_POWER"GND"
BODY_TYPE"PLUMBING"
CDS_LIB"mstr_symbols"
VOLTAGE"0"
ROOM"VDDQ_ABC_PWR_VR"
BOM_COST"PROC_VRD_VCCIN_CPU0"
SIZE"1B";
"A\NAC"4;
%"PVDDQ_DEF"
"1","(-3800,2150)","0","mstr_symbols","I29";
;
HDL_POWER"PVDDQ_DEF"
BODY_TYPE"PLUMBING"
VOLTAGE"1.2V"
BOM_COST"PROC_SOCKET "
ROOM"VDDQ_DEF_PWR_VR"
CDS_LIB"mstr_symbols";
"G\NAC"5;
%"PVDDQ_ABC"
"1","(-7750,2150)","0","mstr_symbols","I3";
;
HDL_POWER"PVDDQ_ABC"
BODY_TYPE"PLUMBING"
CDS_LIB"mstr_symbols"
ROOM"VDDQ_ABC_PWR_VR"
BOM_COST"PROC_SOCKET "
VOLTAGE"1.2V";
"G\NAC"6;
%"GND"
"1","(-3800,2400)","0","mstr_symbols","I33";
;
HDL_POWER"GND"
BODY_TYPE"PLUMBING"
VOLTAGE"0"
ROOM"VDDQ_ABC_PWR_VR"
BOM_COST"PROC_VRD_VCCIN_CPU0"
SIZE"1B"
CDS_LIB"mstr_symbols";
"A\NAC"7;
%"PVDDQ_DEF"
"1","(-3800,3100)","0","mstr_symbols","I35";
;
HDL_POWER"PVDDQ_DEF"
BODY_TYPE"PLUMBING"
ROOM"VDDQ_DEF_PWR_VR"
BOM_COST"PROC_SOCKET "
VOLTAGE"1.2V"
CDS_LIB"mstr_symbols";
"G\NAC"8;
%"GND"
"1","(-3800,3350)","0","mstr_symbols","I36";
;
HDL_POWER"GND"
BODY_TYPE"PLUMBING"
VOLTAGE"0"
ROOM"VDDQ_ABC_PWR_VR"
BOM_COST"PROC_VRD_VCCIN_CPU0"
SIZE"1B"
CDS_LIB"mstr_symbols";
"A\NAC"9;
%"PVDDQ_DEF"
"1","(-3800,4050)","0","mstr_symbols","I50";
;
HDL_POWER"PVDDQ_DEF"
BODY_TYPE"PLUMBING"
ROOM"VDDQ_DEF_PWR_VR"
BOM_COST"PROC_SOCKET "
VOLTAGE"1.2V"
CDS_LIB"mstr_symbols";
"G\NAC"10;
%"CAP_A"
"1","(-7750,2800)","0","dev_discrete","I53";
;
CDS_SEC"1"
CDS_LOCATION"C5G41"
LOCATION"C5G41"
TOLERANCE"20%"
MATERIAL"X6S"
PACK_TYPE"0603V"
VOLTAGE"4V"
VALUE"22.0UF"
GROUP"PWR_MLCC_CAP"
PART_NUMBER"E15431-004"
BOM_DS"NOPOP"
SEC_TYPE"0603V"
SEC"1"
CDS_LIB"dev_discrete"
ROOM"PVDDQ_KLM";
"B"
$PN"2"11;
"A"
$PN"1"12;
%"CAP_A"
"1","(-7350,2800)","0","dev_discrete","I54";
;
CDS_SEC"1"
CDS_LOCATION"C5G42"
GROUP"PWR_MLCC_CAP"
PART_NUMBER"E15431-004"
LOCATION"C5G42"
TOLERANCE"20%"
VALUE"22.0UF"
VOLTAGE"4V"
PACK_TYPE"0603V"
MATERIAL"X6S"
BOM_DS"NOPOP"
ROOM"PVDDQ_KLM"
CDS_LIB"dev_discrete"
SEC"1"
SEC_TYPE"0603V";
"B"
$PN"2"11;
"A"
$PN"1"12;
%"CAP_A"
"1","(-6550,2800)","0","dev_discrete","I55";
;
CDS_SEC"1"
CDS_LOCATION"C5G44"
GROUP"PWR_MLCC_CAP"
VALUE"22.0UF"
MATERIAL"X6S"
LOCATION"C5G44"
PACK_TYPE"0603V"
PART_NUMBER"E15431-004"
TOLERANCE"20%"
VOLTAGE"4V"
BOM_DS"NOPOP"
SEC_TYPE"0603V"
SEC"1"
ROOM"PVDDQ_KLM"
CDS_LIB"dev_discrete";
"B"
$PN"2"11;
"A"
$PN"1"12;
%"CAP_A"
"1","(-6950,2800)","0","dev_discrete","I56";
;
CDS_SEC"1"
CDS_LOCATION"C5G43"
GROUP"PWR_MLCC_CAP"
VOLTAGE"4V"
PART_NUMBER"E15431-004"
PACK_TYPE"0603V"
MATERIAL"X6S"
TOLERANCE"20%"
VALUE"22.0UF"
LOCATION"C5G43"
BOM_DS"NOPOP"
SEC_TYPE"0603V"
SEC"1"
CDS_LIB"dev_discrete"
ROOM"PVDDQ_KLM";
"B"
$PN"2"11;
"A"
$PN"1"12;
%"CAP_A"
"1","(-4950,2800)","0","dev_discrete","I57";
;
CDS_SEC"1"
CDS_LOCATION"C5G48"
GROUP"PWR_MLCC_CAP"
PART_NUMBER"E15431-004"
MATERIAL"X6S"
PACK_TYPE"0603V"
TOLERANCE"20%"
LOCATION"C5G48"
VOLTAGE"4V"
VALUE"22.0UF"
BOM_DS"NOPOP"
SEC_TYPE"0603V"
SEC"1"
ROOM"PVDDQ_KLM"
CDS_LIB"dev_discrete";
"B"
$PN"2"11;
"A"
$PN"1"12;
%"CAP_A"
"1","(-5350,2800)","0","dev_discrete","I58";
;
CDS_SEC"1"
CDS_LOCATION"C5G47"
GROUP"PWR_MLCC_CAP"
PACK_TYPE"0603V"
PART_NUMBER"E15431-004"
VOLTAGE"4V"
TOLERANCE"20%"
MATERIAL"X6S"
VALUE"22.0UF"
LOCATION"C5G47"
BOM_DS"NOPOP"
CDS_LIB"dev_discrete"
ROOM"PVDDQ_KLM"
SEC"1"
SEC_TYPE"0603V";
"B"
$PN"2"11;
"A"
$PN"1"12;
%"CAP_A"
"1","(-5750,2800)","0","dev_discrete","I59";
;
CDS_SEC"1"
CDS_LOCATION"C5G46"
GROUP"PWR_MLCC_CAP"
LOCATION"C5G46"
VOLTAGE"4V"
PART_NUMBER"E15431-004"
PACK_TYPE"0603V"
TOLERANCE"20%"
MATERIAL"X6S"
VALUE"22.0UF"
BOM_DS"NOPOP"
SEC_TYPE"0603V"
SEC"1"
ROOM"PVDDQ_KLM"
CDS_LIB"dev_discrete";
"B"
$PN"2"11;
"A"
$PN"1"12;
%"CAP_A"
"1","(-6150,2800)","0","dev_discrete","I60";
;
CDS_SEC"1"
CDS_LOCATION"C5G45"
GROUP"PWR_MLCC_CAP"
PART_NUMBER"E15431-004"
PACK_TYPE"0603V"
LOCATION"C5G45"
TOLERANCE"20%"
MATERIAL"X6S"
VALUE"22.0UF"
VOLTAGE"4V"
BOM_DS"NOPOP"
SEC_TYPE"0603V"
SEC"1"
ROOM"PVDDQ_KLM"
CDS_LIB"dev_discrete";
"B"
$PN"2"11;
"A"
$PN"1"12;
%"CAP_A"
"1","(-4550,2800)","0","dev_discrete","I61";
;
CDS_SEC"1"
CDS_LOCATION"C5G49"
GROUP"PWR_MLCC_CAP"
PART_NUMBER"E15431-004"
TOLERANCE"20%"
MATERIAL"X6S"
PACK_TYPE"0603V"
LOCATION"C5G49"
VOLTAGE"4V"
VALUE"22.0UF"
BOM_DS"NOPOP"
CDS_LIB"dev_discrete"
ROOM"PVDDQ_KLM"
SEC"1"
SEC_TYPE"0603V";
"B"
$PN"2"11;
"A"
$PN"1"12;
%"CAP_A"
"1","(-6150,1850)","0","dev_discrete","I62";
;
CDS_SEC"1"
CDS_LOCATION"C5G54"
PACK_TYPE"0603V"
MATERIAL"X6S"
TOLERANCE"20%"
VALUE"22.0UF"
VOLTAGE"4V"
LOCATION"C5G54"
GROUP"PWR_MLCC_CAP"
PART_NUMBER"E15431-004"
BOM_DS"NOPOP"
SEC_TYPE"0603V"
SEC"1"
ROOM"PVDDQ_KLM"
CDS_LIB"dev_discrete";
"B"
$PN"2"2;
"A"
$PN"1"6;
%"CAP_A"
"1","(-4550,1850)","0","dev_discrete","I63";
;
CDS_SEC"1"
CDS_LOCATION"C5G58"
GROUP"PWR_MLCC_CAP"
TOLERANCE"20%"
VOLTAGE"4V"
MATERIAL"X6S"
VALUE"22.0UF"
PACK_TYPE"0603V"
LOCATION"C5G58"
PART_NUMBER"E15431-004"
BOM_DS"NOPOP"
CDS_LIB"dev_discrete"
ROOM"PVDDQ_KLM"
SEC"1"
SEC_TYPE"0603V";
"B"
$PN"2"2;
"A"
$PN"1"6;
%"CAP_A"
"1","(-4950,1850)","0","dev_discrete","I64";
;
CDS_SEC"1"
CDS_LOCATION"C5G57"
GROUP"PWR_MLCC_CAP"
MATERIAL"X6S"
PART_NUMBER"E15431-004"
PACK_TYPE"0603V"
VALUE"22.0UF"
TOLERANCE"20%"
LOCATION"C5G57"
VOLTAGE"4V"
BOM_DS"NOPOP"
SEC_TYPE"0603V"
SEC"1"
ROOM"PVDDQ_KLM"
CDS_LIB"dev_discrete";
"B"
$PN"2"2;
"A"
$PN"1"6;
%"CAP_A"
"1","(-5350,1850)","0","dev_discrete","I65";
;
CDS_SEC"1"
CDS_LOCATION"C5G56"
GROUP"PWR_MLCC_CAP"
LOCATION"C5G56"
PART_NUMBER"E15431-004"
TOLERANCE"20%"
VOLTAGE"4V"
VALUE"22.0UF"
MATERIAL"X6S"
PACK_TYPE"0603V"
BOM_DS"NOPOP"
CDS_LIB"dev_discrete"
ROOM"PVDDQ_KLM"
SEC"1"
SEC_TYPE"0603V";
"B"
$PN"2"2;
"A"
$PN"1"6;
%"CAP_A"
"1","(-5750,1850)","0","dev_discrete","I66";
;
CDS_SEC"1"
CDS_LOCATION"C5G55"
GROUP"PWR_MLCC_CAP"
PART_NUMBER"E15431-004"
TOLERANCE"20%"
PACK_TYPE"0603V"
MATERIAL"X6S"
VOLTAGE"4V"
VALUE"22.0UF"
LOCATION"C5G55"
BOM_DS"NOPOP"
SEC_TYPE"0603V"
SEC"1"
ROOM"PVDDQ_KLM"
CDS_LIB"dev_discrete";
"B"
$PN"2"2;
"A"
$PN"1"6;
%"CAP_A"
"1","(-6550,1850)","0","dev_discrete","I67";
;
CDS_SEC"1"
CDS_LOCATION"C5G53"
GROUP"PWR_MLCC_CAP"
TOLERANCE"20%"
PART_NUMBER"E15431-004"
PACK_TYPE"0603V"
VOLTAGE"4V"
MATERIAL"X6S"
LOCATION"C5G53"
VALUE"22.0UF"
BOM_DS"NOPOP"
SEC_TYPE"0603V"
SEC"1"
ROOM"PVDDQ_KLM"
CDS_LIB"dev_discrete";
"B"
$PN"2"2;
"A"
$PN"1"6;
%"CAP_A"
"1","(-6950,1850)","0","dev_discrete","I68";
;
CDS_SEC"1"
CDS_LOCATION"C5G52"
GROUP"PWR_MLCC_CAP"
VALUE"22.0UF"
VOLTAGE"4V"
TOLERANCE"20%"
LOCATION"C5G52"
PACK_TYPE"0603V"
MATERIAL"X6S"
PART_NUMBER"E15431-004"
BOM_DS"NOPOP"
SEC_TYPE"0603V"
SEC"1"
CDS_LIB"dev_discrete"
ROOM"PVDDQ_KLM";
"B"
$PN"2"2;
"A"
$PN"1"6;
%"CAP_A"
"1","(-7350,1850)","0","dev_discrete","I69";
;
CDS_SEC"1"
CDS_LOCATION"C5G51"
GROUP"PWR_MLCC_CAP"
VALUE"22.0UF"
VOLTAGE"4V"
TOLERANCE"20%"
LOCATION"C5G51"
PART_NUMBER"E15431-004"
MATERIAL"X6S"
PACK_TYPE"0603V"
BOM_DS"NOPOP"
ROOM"PVDDQ_KLM"
CDS_LIB"dev_discrete"
SEC"1"
SEC_TYPE"0603V";
"B"
$PN"2"2;
"A"
$PN"1"6;
%"GND"
"1","(-7750,2400)","0","mstr_symbols","I7";
;
HDL_POWER"GND"
BODY_TYPE"PLUMBING"
CDS_LIB"mstr_symbols"
SIZE"1B"
BOM_COST"PROC_VRD_VCCIN_CPU0"
ROOM"VDDQ_ABC_PWR_VR"
VOLTAGE"0";
"A\NAC"11;
%"CAP_A"
"1","(-7750,1850)","0","dev_discrete","I70";
;
CDS_SEC"1"
CDS_LOCATION"C5G50"
GROUP"PWR_MLCC_CAP"
PART_NUMBER"E15431-004"
PACK_TYPE"0603V"
MATERIAL"X6S"
TOLERANCE"20%"
VALUE"22.0UF"
LOCATION"C5G50"
VOLTAGE"4V"
BOM_DS"NOPOP"
ROOM"PVDDQ_KLM"
CDS_LIB"dev_discrete"
SEC"1"
SEC_TYPE"0603V";
"B"
$PN"2"2;
"A"
$PN"1"6;
%"CAP_A"
"1","(-600,2800)","0","dev_discrete","I71";
;
CDS_SEC"1"
CDS_LOCATION"C5G67"
LOCATION"C5G67"
VALUE"22.0UF"
TOLERANCE"20%"
VOLTAGE"4V"
PART_NUMBER"E15431-004"
MATERIAL"X6S"
PACK_TYPE"0603V"
GROUP"PWR_MLCC_CAP"
BOM_DS"NOPOP"
ROOM"PVDDQ_KLM"
CDS_LIB"dev_discrete"
SEC"1"
SEC_TYPE"0603V";
"B"
$PN"2"7;
"A"
$PN"1"8;
%"CAP_A"
"1","(-1000,2800)","0","dev_discrete","I72";
;
CDS_SEC"1"
CDS_LOCATION"C5G66"
VOLTAGE"4V"
VALUE"22.0UF"
MATERIAL"X6S"
PACK_TYPE"0603V"
LOCATION"C5G66"
TOLERANCE"20%"
PART_NUMBER"E15431-004"
GROUP"PWR_MLCC_CAP"
BOM_DS"NOPOP"
SEC_TYPE"0603V"
SEC"1"
CDS_LIB"dev_discrete"
ROOM"PVDDQ_KLM";
"B"
$PN"2"7;
"A"
$PN"1"8;
%"CAP_A"
"1","(-1400,2800)","0","dev_discrete","I73";
;
CDS_SEC"1"
CDS_LOCATION"C5G65"
LOCATION"C5G65"
VALUE"22.0UF"
PART_NUMBER"E15431-004"
MATERIAL"X6S"
PACK_TYPE"0603V"
VOLTAGE"4V"
TOLERANCE"20%"
GROUP"PWR_MLCC_CAP"
BOM_DS"NOPOP"
ROOM"PVDDQ_KLM"
CDS_LIB"dev_discrete"
SEC"1"
SEC_TYPE"0603V";
"B"
$PN"2"7;
"A"
$PN"1"8;
%"CAP_A"
"1","(-1800,2800)","0","dev_discrete","I74";
;
CDS_SEC"1"
CDS_LOCATION"C5G64"
PACK_TYPE"0603V"
PART_NUMBER"E15431-004"
LOCATION"C5G64"
VALUE"22.0UF"
MATERIAL"X6S"
VOLTAGE"4V"
TOLERANCE"20%"
GROUP"PWR_MLCC_CAP"
BOM_DS"NOPOP"
SEC_TYPE"0603V"
SEC"1"
CDS_LIB"dev_discrete"
ROOM"PVDDQ_KLM";
"B"
$PN"2"7;
"A"
$PN"1"8;
%"CAP_A"
"1","(-2200,2800)","0","dev_discrete","I75";
;
CDS_SEC"1"
CDS_LOCATION"C5G63"
VALUE"22.0UF"
TOLERANCE"20%"
VOLTAGE"4V"
PACK_TYPE"0603V"
PART_NUMBER"E15431-004"
MATERIAL"X6S"
LOCATION"C5G63"
GROUP"PWR_MLCC_CAP"
BOM_DS"NOPOP"
ROOM"PVDDQ_KLM"
CDS_LIB"dev_discrete"
SEC"1"
SEC_TYPE"0603V";
"B"
$PN"2"7;
"A"
$PN"1"8;
%"CAP_A"
"1","(-2600,2800)","0","dev_discrete","I76";
;
CDS_SEC"1"
CDS_LOCATION"C5G62"
VOLTAGE"4V"
PACK_TYPE"0603V"
PART_NUMBER"E15431-004"
MATERIAL"X6S"
TOLERANCE"20%"
GROUP"PWR_MLCC_CAP"
VALUE"22.0UF"
LOCATION"C5G62"
BOM_DS"NOPOP"
SEC_TYPE"0603V"
SEC"1"
CDS_LIB"dev_discrete"
ROOM"PVDDQ_KLM";
"B"
$PN"2"7;
"A"
$PN"1"8;
%"CAP_A"
"1","(-3000,2800)","0","dev_discrete","I77";
;
CDS_SEC"1"
CDS_LOCATION"C5G61"
PACK_TYPE"0603V"
VOLTAGE"4V"
VALUE"22.0UF"
LOCATION"C5G61"
TOLERANCE"20%"
GROUP"PWR_MLCC_CAP"
PART_NUMBER"E15431-004"
MATERIAL"X6S"
BOM_DS"NOPOP"
CDS_LIB"dev_discrete"
ROOM"PVDDQ_KLM"
SEC"1"
SEC_TYPE"0603V";
"B"
$PN"2"7;
"A"
$PN"1"8;
%"CAP_A"
"1","(-3400,2800)","0","dev_discrete","I78";
;
CDS_SEC"1"
CDS_LOCATION"C5G60"
MATERIAL"X6S"
PACK_TYPE"0603V"
PART_NUMBER"E15431-004"
GROUP"PWR_MLCC_CAP"
TOLERANCE"20%"
VOLTAGE"4V"
VALUE"22.0UF"
LOCATION"C5G60"
BOM_DS"NOPOP"
SEC_TYPE"0603V"
SEC"1"
ROOM"PVDDQ_KLM"
CDS_LIB"dev_discrete";
"B"
$PN"2"7;
"A"
$PN"1"8;
%"CAP_A"
"1","(-3800,2800)","0","dev_discrete","I79";
;
CDS_SEC"1"
CDS_LOCATION"C5G59"
VOLTAGE"4V"
VALUE"22.0UF"
MATERIAL"X6S"
TOLERANCE"20%"
LOCATION"C5G59"
GROUP"PWR_MLCC_CAP"
PACK_TYPE"0603V"
PART_NUMBER"E15431-004"
BOM_DS"NOPOP"
CDS_LIB"dev_discrete"
ROOM"PVDDQ_KLM"
SEC"1"
SEC_TYPE"0603V";
"B"
$PN"2"7;
"A"
$PN"1"8;
%"CAP_A"
"1","(-600,1850)","0","dev_discrete","I80";
;
CDS_SEC"1"
CDS_LOCATION"C5G76"
VOLTAGE"4V"
TOLERANCE"20%"
MATERIAL"X6S"
LOCATION"C5G76"
VALUE"22.0UF"
GROUP"PWR_MLCC_CAP"
PACK_TYPE"0603V"
PART_NUMBER"E15431-004"
BOM_DS"NOPOP"
SEC_TYPE"0603V"
SEC"1"
ROOM"PVDDQ_KLM"
CDS_LIB"dev_discrete";
"B"
$PN"2"4;
"A"
$PN"1"5;
%"CAP_A"
"1","(-1000,1850)","0","dev_discrete","I81";
;
CDS_SEC"1"
CDS_LOCATION"C5G75"
PACK_TYPE"0603V"
LOCATION"C5G75"
VALUE"22.0UF"
PART_NUMBER"E15431-004"
MATERIAL"X6S"
TOLERANCE"20%"
VOLTAGE"4V"
GROUP"PWR_MLCC_CAP"
BOM_DS"NOPOP"
CDS_LIB"dev_discrete"
ROOM"PVDDQ_KLM"
SEC"1"
SEC_TYPE"0603V";
"B"
$PN"2"4;
"A"
$PN"1"5;
%"CAP_A"
"1","(-1400,1850)","0","dev_discrete","I82";
;
CDS_SEC"1"
CDS_LOCATION"C5G74"
PACK_TYPE"0603V"
VALUE"22.0UF"
TOLERANCE"20%"
VOLTAGE"4V"
MATERIAL"X6S"
LOCATION"C5G74"
PART_NUMBER"E15431-004"
GROUP"PWR_MLCC_CAP"
BOM_DS"NOPOP"
SEC_TYPE"0603V"
SEC"1"
ROOM"PVDDQ_KLM"
CDS_LIB"dev_discrete";
"B"
$PN"2"4;
"A"
$PN"1"5;
%"CAP_A"
"1","(-1800,1850)","0","dev_discrete","I83";
;
CDS_SEC"1"
CDS_LOCATION"C5G73"
PART_NUMBER"E15431-004"
LOCATION"C5G73"
MATERIAL"X6S"
VOLTAGE"4V"
TOLERANCE"20%"
PACK_TYPE"0603V"
VALUE"22.0UF"
GROUP"PWR_MLCC_CAP"
BOM_DS"NOPOP"
CDS_LIB"dev_discrete"
ROOM"PVDDQ_KLM"
SEC"1"
SEC_TYPE"0603V";
"B"
$PN"2"4;
"A"
$PN"1"5;
%"CAP_A"
"1","(-2200,1850)","0","dev_discrete","I84";
;
CDS_SEC"1"
CDS_LOCATION"C5G72"
PACK_TYPE"0603V"
PART_NUMBER"E15431-004"
MATERIAL"X6S"
TOLERANCE"20%"
VALUE"22.0UF"
LOCATION"C5G72"
VOLTAGE"4V"
GROUP"PWR_MLCC_CAP"
BOM_DS"NOPOP"
SEC_TYPE"0603V"
SEC"1"
ROOM"PVDDQ_KLM"
CDS_LIB"dev_discrete";
"B"
$PN"2"4;
"A"
$PN"1"5;
%"CAP_A"
"1","(-2600,1850)","0","dev_discrete","I85";
;
CDS_SEC"1"
CDS_LOCATION"C5G71"
VALUE"22.0UF"
VOLTAGE"4V"
MATERIAL"X6S"
TOLERANCE"20%"
PART_NUMBER"E15431-004"
PACK_TYPE"0603V"
LOCATION"C5G71"
GROUP"PWR_MLCC_CAP"
BOM_DS"NOPOP"
CDS_LIB"dev_discrete"
ROOM"PVDDQ_KLM"
SEC"1"
SEC_TYPE"0603V";
"B"
$PN"2"4;
"A"
$PN"1"5;
%"CAP_A"
"1","(-3000,1850)","0","dev_discrete","I86";
;
CDS_SEC"1"
CDS_LOCATION"C5G70"
LOCATION"C5G70"
VALUE"22.0UF"
PART_NUMBER"E15431-004"
TOLERANCE"20%"
MATERIAL"X6S"
PACK_TYPE"0603V"
GROUP"PWR_MLCC_CAP"
VOLTAGE"4V"
BOM_DS"NOPOP"
SEC_TYPE"0603V"
SEC"1"
CDS_LIB"dev_discrete"
ROOM"PVDDQ_KLM";
"B"
$PN"2"4;
"A"
$PN"1"5;
%"CAP_A"
"1","(-3400,1850)","0","dev_discrete","I87";
;
CDS_SEC"1"
CDS_LOCATION"C5G69"
MATERIAL"X6S"
TOLERANCE"20%"
GROUP"PWR_MLCC_CAP"
PACK_TYPE"0603V"
PART_NUMBER"E15431-004"
VOLTAGE"4V"
VALUE"22.0UF"
LOCATION"C5G69"
BOM_DS"NOPOP"
ROOM"PVDDQ_KLM"
CDS_LIB"dev_discrete"
SEC"1"
SEC_TYPE"0603V";
"B"
$PN"2"4;
"A"
$PN"1"5;
%"CAP_A"
"1","(-3800,1850)","0","dev_discrete","I88";
;
CDS_SEC"1"
CDS_LOCATION"C5G68"
MATERIAL"X6S"
PACK_TYPE"0603V"
PART_NUMBER"E15431-004"
LOCATION"C5G68"
VOLTAGE"4V"
TOLERANCE"20%"
VALUE"22.0UF"
GROUP"PWR_MLCC_CAP"
BOM_DS"NOPOP"
SEC_TYPE"0603V"
SEC"1"
CDS_LIB"dev_discrete"
ROOM"PVDDQ_KLM";
"B"
$PN"2"4;
"A"
$PN"1"5;
%"CAP"
"1","(-3800,3775)","0","mstr_discrete","I89";
;
CDS_SEC"1"
CDS_LOCATION"C5G77"
LOCATION"C5G77"
VOLTAGE"4V"
VALUE"47UF"
TOLERANCE"20%"
MATERIAL"X6S"
PACK_TYPE"0805"
PART_NUMBER"C95333-006"
POP"NOPOP"
GROUP"PWR_MLCC_CAP"
CDS_LIB"mstr_discrete"
ROOM"PVCCIN_CPU0_DECAP_VR"
BOM_COST"PROC_SOCKET"
SEC"1"
SEC_TYPE"0805";
"A"
$PN"1"10;
"B"
$PN"2"9;
%"PVDDQ_ABC"
"1","(-7750,3125)","0","mstr_symbols","I9";
;
HDL_POWER"PVDDQ_ABC"
BODY_TYPE"PLUMBING"
VOLTAGE"1.2V"
BOM_COST"PROC_SOCKET "
ROOM"VDDQ_ABC_PWR_VR"
CDS_LIB"mstr_symbols";
"G\NAC"12;
%"CAP"
"1","(-7350,3775)","0","mstr_discrete","I90";
;
CDS_SEC"1"
CDS_LOCATION"C5G22"
PART_NUMBER"C95333-006"
VALUE"47UF"
VOLTAGE"4V"
POP"NOPOP"
LOCATION"C5G22"
MATERIAL"X6S"
PACK_TYPE"0805"
TOLERANCE"20%"
GROUP"PWR_MLCC_CAP"
SEC_TYPE"0805"
SEC"1"
ROOM"PVCCIN_CPU0_DECAP_VR"
BOM_COST"PROC_SOCKET"
CDS_LIB"mstr_discrete";
"A"
$PN"1"1;
"B"
$PN"2"3;
%"CAP"
"1","(-3400,3775)","0","mstr_discrete","I91";
;
CDS_SEC"1"
CDS_LOCATION"C5G78"
POP"NOPOP"
VOLTAGE"4V"
TOLERANCE"20%"
PACK_TYPE"0805"
VALUE"47UF"
PART_NUMBER"C95333-006"
GROUP"PWR_MLCC_CAP"
LOCATION"C5G78"
MATERIAL"X6S"
BOM_COST"PROC_SOCKET"
ROOM"PVCCIN_CPU0_DECAP_VR"
CDS_LIB"mstr_discrete"
SEC"1"
SEC_TYPE"0805";
"A"
$PN"1"10;
"B"
$PN"2"9;
%"CAP"
"1","(-7750,3775)","0","mstr_discrete","I92";
;
CDS_SEC"1"
CDS_LOCATION"C5G21"
GROUP"PWR_MLCC_CAP"
POP"NOPOP"
PART_NUMBER"C95333-006"
VOLTAGE"4V"
TOLERANCE"20%"
VALUE"47UF"
LOCATION"C5G21"
MATERIAL"X6S"
PACK_TYPE"0805"
SEC_TYPE"0805"
SEC"1"
CDS_LIB"mstr_discrete"
ROOM"PVCCIN_CPU0_DECAP_VR"
BOM_COST"PROC_SOCKET";
"A"
$PN"1"1;
"B"
$PN"2"3;
END.
